# T6G (Grand Teton) — schematic netlist excerpt (pin names and nets, part order shuffled) for the footprints in the layout excerpt that follows; sources: Cadence DE-HDL packaged netlist, KiCad conversion of 04192023_DAF0TMB3IC0_F0TG_MB_C_brd_V02_OCP.brd

R6013  Q_RES  0 5% CHIP  pkg 0402LF  page 150 : A = SGPIO_SCM_CLK_<1> ; B = SGPIO_SCM_CLK_R_<1>
R927  Q_RES  1K 1% EMPTY  pkg 0201LF  page 353 : A = P1V8_CPU1_RT_1D ; B = RT_CPU1_P3_ADDR1

U100  RT9818C44GV  RT9818C-44GV IC  pkg SOT23_123_2-89X1-6  page 188
  \reset#\  = PWRGD_P5V_R
  GND  = GND
  VDD  = P5V

(kicad_pcb
	(version 20260206)
	(generator "pcbnew")
	(generator_version "10.0")
	(general
		(thickness 1.6)
		(legacy_teardrops no)
	)
	(paper "A4")
	(title_block
		(title "04192023_DAF0TMB3IC0_F0TG_MB_C_brd_V02_OCP.brd")
		(comment 1 "Grand Teton / footprints 2627-2629 of 8354")
	)
	(layers
		(0 "F.Cu" signal "TOP")
		(4 "In1.Cu" signal "GND")
		(6 "In2.Cu" signal "IN1")
		(8 "In3.Cu" signal "GND1")
		(10 "In4.Cu" signal "IN2")
		(12 "In5.Cu" signal "GND2")
		(14 "In6.Cu" signal "IN3")
		(16 "In7.Cu" signal "GND3")
		(18 "In8.Cu" signal "VCC")
		(20 "In9.Cu" signal "VCC1")
		(22 "In10.Cu" signal "GND4")
		(24 "In11.Cu" signal "IN4")
		(26 "In12.Cu" signal "GND5")
		(28 "In13.Cu" signal "IN5")
		(30 "In14.Cu" signal "GND6")
		(32 "In15.Cu" signal "IN6")
		(34 "In16.Cu" signal "GND7")
		(2 "B.Cu" signal "BOTTOM")
		(9 "F.Adhes" user "F.Adhesive")
		(11 "B.Adhes" user "B.Adhesive")
		(13 "F.Paste" user "Package Geometry/Pastemask Top")
		(15 "B.Paste" user "Package Geometry/Pastemask Bottom")
		(5 "F.SilkS" user "Ref Des/Silkscreen Top")
		(7 "B.SilkS" user "Ref Des/Silkscreen Bottom")
		(1 "F.Mask" user "Board Geometry/Soldermask Top")
		(3 "B.Mask" user "Board Geometry/Soldermask Bottom")
		(17 "Dwgs.User" user "User.Drawings")
		(19 "Cmts.User" user "User.Comments")
		(21 "Eco1.User" user "User.Eco1")
		(23 "Eco2.User" user "User.Eco2")
		(25 "Edge.Cuts" user "Board Geometry/Outline")
		(27 "Margin" user)
		(31 "F.CrtYd" user "Package Geometry/Place Bound Top")
		(29 "B.CrtYd" user "Package Geometry/Place Bound Bottom")
		(35 "F.Fab" user "Ref Des/Assembly Top")
		(33 "B.Fab" user "Ref Des/Assembly Bottom")
	)
	(footprint ""
		(layer "F.Cu")
		(at 169.799 -132.08)
		(property "Reference" "U100"
			(at -5.050536 -1.718564 0)
			(unlocked yes)
			(layer "F.SilkS")
			(effects
				(font
					(size 0.7874 0.5842)
					(thickness 0.1524)
				)
				(justify left)
			)
		)
		(property "Value" ""
			(at 0 0 0)
			(layer "F.Fab")
			(effects
				(font
					(size 1.27 1.27)
				)
			)
		)
		(duplicate_pad_numbers_are_jumpers no)
		(fp_line
			(start -1.934972 -1.5494)
			(end 1.934972 -1.5494)
			(stroke
				(width 0.1524)
				(type default)
			)
			(layer "F.SilkS")
		)
		(fp_line
			(start -1.934972 1.5494)
			(end -1.934972 -1.5494)
			(stroke
				(width 0.1524)
				(type default)
			)
			(layer "F.SilkS")
		)
		(fp_line
			(start 1.934972 -1.5494)
			(end 1.934972 1.5494)
			(stroke
				(width 0.1524)
				(type default)
			)
			(layer "F.SilkS")
		)
		(fp_line
			(start 1.934972 1.5494)
			(end -1.934972 1.5494)
			(stroke
				(width 0.1524)
				(type default)
			)
			(layer "F.SilkS")
		)
		(fp_line
			(start -0.901446 -1.5494)
			(end 0.901446 -1.5494)
			(stroke
				(width 0.1)
				(type default)
			)
			(layer "F.Fab")
		)
		(fp_line
			(start -0.901446 1.5494)
			(end -0.901446 -1.5494)
			(stroke
				(width 0.1)
				(type default)
			)
			(layer "F.Fab")
		)
		(fp_line
			(start 0.901446 -1.5494)
			(end 0.901446 1.5494)
			(stroke
				(width 0.1)
				(type default)
			)
			(layer "F.Fab")
		)
		(fp_line
			(start 0.901446 1.5494)
			(end -0.901446 1.5494)
			(stroke
				(width 0.1)
				(type default)
			)
			(layer "F.Fab")
		)
		(pad "1" smd rect
			(at -1.299972 -0.94996 270)
			(size 0.8128 1.016)
			(layers "F.Cu" "F.Mask" "F.Paste")
			(net "PWRGD_P5V_R")
		)
		(pad "2" smd rect
			(at -1.299972 0.94996 270)
			(size 0.8128 1.016)
			(layers "F.Cu" "F.Mask" "F.Paste")
			(net "GND")
		)
		(pad "3" smd rect
			(at 1.299972 0 270)
			(size 0.8128 1.016)
			(layers "F.Cu" "F.Mask" "F.Paste")
			(net "P5V")
		)
	)
	(footprint ""
		(layer "F.Cu")
		(at 171.9072 -94.833948 -90)
		(property "Reference" "R6013"
			(at 0 0 270)
			(layer "F.SilkS")
			(hide yes)
			(effects
				(font
					(size 1.27 1.27)
				)
			)
		)
		(property "Value" ""
			(at 0 0 270)
			(layer "F.Fab")
			(effects
				(font
					(size 1.27 1.27)
				)
			)
		)
		(duplicate_pad_numbers_are_jumpers no)
		(fp_line
			(start -0.7874 0.4064)
			(end -0.7874 -0.4064)
			(stroke
				(width 0.1524)
				(type default)
			)
			(layer "F.SilkS")
		)
		(fp_line
			(start 0.7874 0.4064)
			(end -0.7874 0.4064)
			(stroke
				(width 0.1524)
				(type default)
			)
			(layer "F.SilkS")
		)
		(fp_line
			(start -0.7874 -0.4064)
			(end 0.7874 -0.4064)
			(stroke
				(width 0.1524)
				(type default)
			)
			(layer "F.SilkS")
		)
		(fp_line
			(start 0.7874 -0.4064)
			(end 0.7874 0.4064)
			(stroke
				(width 0.1524)
				(type default)
			)
			(layer "F.SilkS")
		)
		(fp_line
			(start -0.67945 0.3048)
			(end -0.67945 -0.305054)
			(stroke
				(width 0.1)
				(type default)
			)
			(layer "F.Fab")
		)
		(fp_line
			(start -0.12065 0.3048)
			(end -0.67945 0.3048)
			(stroke
				(width 0.1)
				(type default)
			)
			(layer "F.Fab")
		)
		(fp_line
			(start 0.120396 0.3048)
			(end 0.120396 0.2794)
			(stroke
				(width 0.1)
				(type default)
			)
			(layer "F.Fab")
		)
		(fp_line
			(start 0.67945 0.3048)
			(end 0.120396 0.3048)
			(stroke
				(width 0.1)
				(type default)
			)
			(layer "F.Fab")
		)
		(fp_line
			(start -0.12065 0.2794)
			(end -0.12065 0.3048)
			(stroke
				(width 0.1)
				(type default)
			)
			(layer "F.Fab")
		)
		(fp_line
			(start 0.120396 0.2794)
			(end -0.12065 0.2794)
			(stroke
				(width 0.1)
				(type default)
			)
			(layer "F.Fab")
		)
		(fp_line
			(start -0.12065 -0.2794)
			(end 0.12065 -0.2794)
			(stroke
				(width 0.1)
				(type default)
			)
			(layer "F.Fab")
		)
		(fp_line
			(start 0.12065 -0.2794)
			(end 0.12065 -0.3048)
			(stroke
				(width 0.1)
				(type default)
			)
			(layer "F.Fab")
		)
		(fp_line
			(start 0.12065 -0.3048)
			(end 0.67945 -0.3048)
			(stroke
				(width 0.1)
				(type default)
			)
			(layer "F.Fab")
		)
		(fp_line
			(start 0.67945 -0.3048)
			(end 0.67945 0.3048)
			(stroke
				(width 0.1)
				(type default)
			)
			(layer "F.Fab")
		)
		(fp_line
			(start -0.67945 -0.305054)
			(end -0.12065 -0.305054)
			(stroke
				(width 0.1)
				(type default)
			)
			(layer "F.Fab")
		)
		(fp_line
			(start -0.12065 -0.305054)
			(end -0.12065 -0.2794)
			(stroke
				(width 0.1)
				(type default)
			)
			(layer "F.Fab")
		)
		(pad "1" smd circle
			(at -0.40005 0 270)
			(size 0 0)
			(layers "F.Cu" "F.Mask" "F.Paste")
			(net "SGPIO_SCM_CLK_<1>")
		)
		(pad "2" smd circle
			(at 0.40005 0 270)
			(size 0 0)
			(layers "F.Cu" "F.Mask" "F.Paste")
			(net "SGPIO_SCM_CLK_R_<1>")
		)
	)
	(footprint ""
		(layer "F.Cu")
		(at 138.067542 -382.6764 180)
		(property "Reference" "R927"
			(at 0 0 180)
			(layer "F.SilkS")
			(hide yes)
			(effects
				(font
					(size 1.27 1.27)
				)
			)
		)
		(property "Value" ""
			(at 0 0 180)
			(layer "F.Fab")
			(effects
				(font
					(size 1.27 1.27)
				)
			)
		)
		(duplicate_pad_numbers_are_jumpers no)
		(fp_line
			(start 0.32512 0.175006)
			(end -0.32512 0.175006)
			(stroke
				(width 0.1)
				(type default)
			)
			(layer "F.Fab")
		)
		(fp_line
			(start 0.32512 -0.175006)
			(end 0.32512 0.175006)
			(stroke
				(width 0.1)
				(type default)
			)
			(layer "F.Fab")
		)
		(fp_line
			(start -0.32512 0.175006)
			(end -0.32512 -0.175006)
			(stroke
				(width 0.1)
				(type default)
			)
			(layer "F.Fab")
		)
		(fp_line
			(start -0.32512 -0.175006)
			(end 0.32512 -0.175006)
			(stroke
				(width 0.1)
				(type default)
			)
			(layer "F.Fab")
		)
		(pad "1" smd rect
			(at -0.2667 0 180)
			(size 0.3048 0.381)
			(layers "F.Cu" "F.Mask" "F.Paste")
			(net "P1V8_CPU1_RT_1D")
		)
		(pad "2" smd rect
			(at 0.2667 0)
			(size 0.3048 0.381)
			(layers "F.Cu" "F.Mask" "F.Paste")
			(net "RT_CPU1_P3_ADDR1")
		)
	)
)
